FILE_TYPE = CONNECTIVITY;
{Allegro Design Entry HDL 17.2-2016 S066 (3851973) 4/6/2020}
"PAGE_NUMBER" = 524;
0"NC";
1"SG\g";
2"SG\g";
3"SG\g";
4"SG\g";
5"XP3R3V_FPGA\g";
6"XP3R3V_FPGA\g";
7"XP3R3V_FT4232\g";
8"SG\g";
9"SG\g";
10"SG\g";
11"SG\g";
12"XP3R3V_FPGA\g";
13"SG\g";
14"XP3R3V_FPGA\g";
15"SG\g";
16"SG\g";
17"XP3R3V_FPGA\g";
18"SG\g";
19"XP3R3V_FPGA\g";
20"SG\g";
21"SG\g";
22"XP5R0V_FT4232\g";
23"SG\g";
24"XP3R3V_FPGA\g";
25"SG\g";
26"XP5R0V_FT4232\g";
27"SG\g";
28"XP5R0V_FT4232\g";
29"XP3R3V_FT4232\g";
30"XP3R3V_FT4232\g";
31"XP3R3V_FT4232\g";
32"XP3R3V_FT4232\g";
33"XP3R3V_FT4232\g";
34"SG\g";
35"SG\g";
36"SG\g";
37"SG\g";
38"SG\g";
39"SG\g";
40"SG\g";
41"UN$524$POWERMOS3PNCHV1$I445$D";
42"MUX1_SEL";
43"FT_USB_DETECT";
44"FPGA_IO_FT_USBDET_RST_N";
45"FT4232_SPI_CS_N";
46"UN$524$CAPACITOR$I7$2";
47"FTDI_EE_CS";
48"FT4232_SPI_CLK";
49"FT4232_SPI_MOSI";
50"FT4232_CHD_TX";
51"FT4232_CHD_RX";
52"R_FT4232_CHD_RX";
53"R_FT4232_I2C_SDA_OUT";
54"UN$524$FT4232HLREELQFP64$I64$BDBUS5";
55"FT4232_TMS_SPICS_N";
56"FT4232_TDI_MOSI";
57"R_FT4232_CHD_TX";
58"R_FT4232_TDI";
59"R_FT4232_TDO";
60"R_FT4232_TMS";
61"FT4232_MUX1_SEL";
62"R_FT4232_TCK";
63"FT4232_TCK_SCLK";
64"FT4232_MUX2_SEL";
65"FTDI_EE_DAT";
66"FTDI_EE_CLK";
67"UN$524$CAPACITOR$I10$2";
68"UN$524$FT4232HLREELQFP64$I64$REF";
69"FPGA_FLASH_CS_N";
70"FPGA_OUT_MUX1_SEL";
71"FT4232_MUX1_SEL";
72"FPGA_EEPROM_I2C_SCL";
73"FT4232_I2C_SDA";
74"R_FT4232_CHC_RX";
75"FLASH_DQ0_MOSI";
76"FPGA_CFG_INIT_N";
77"DBG_UART_MAC_RX";
78"DBG_UART_GPS_RXD";
79"DBG_UART_MAC_TX";
80"DBG_UART_GPS_TXD";
81"FT4232_VREGOUT";
82"FT_USB_DETECT";
83"FTDI_EE_DO";
84"MUX3_SEL";
85"FPGA_OUT_MUX3_SEL";
86"FT4232_MUX3_SEL";
87"UN$524$RESISTOR$I463$2";
88"FT4232_TMS_SPICS_N";
89"FT4232_TDO_MISO";
90"FT4232_TDI_MOSI";
91"FT4232_TCK_SCLK";
92"FPGA_EEPROM_I2C_SDA";
93"MUX2_SEL";
94"UN$524$RESISTOR$I432$2";
95"FPGA_FLASH_DQ2";
96"FT4232_MUX2_SEL";
97"UART_FT4232_TX_FPGA_RX";
98"XP3R3V_FT_PG";
99"R_FT_USB_DM";
100"FLASH_DQ3";
101"FLASH_DQ2";
102"UN$524$FT4232HLREELQFP64$I64$ADBUS7";
103"UN$524$FT4232HLREELQFP64$I64$BDBUS3";
104"UN$524$FT4232HLREELQFP64$I64$BDBUS4";
105"R_FT_USB_DP";
106"R_FT4232_I2C_SCL";
107"XP3R3V_VPLL";
108"FT4232_I2C_SCL";
109"UART_FT4232_RX_FPGA_TX";
110"EEPROM_I2C_SDA";
111"PCA9546_I2C_SCL";
112"FT4232_MUX3_SEL";
113"R_FT4232_CHC_TX";
114"XP3R3V_VPHY";
115"FT4232_FPGA_TDI";
116"FT4232_FPGA_TCK";
117"UN$524$FT4232HLREELQFP64$I64$BDBUS7";
118"UN$524$FT4232HLREELQFP64$I64$BDBUS6";
119"UN$524$FT4232HLREELQFP64$I64$RESET";
120"FPGA_FLASH_DQ3";
121"FPGA_FLASH_DQ0_MOSI";
122"FT4232_FPGA_TDO";
123"FT_USB_DM";
124"FT4232_FPGA_TMS";
125"FPGA_PCA9546_I2C_SDA";
126"FPGA_FLASH_DQ1_MISO";
127"PCA9546_I2C_SDA";
128"FT_USB_DP";
129"FPGA_OUT_MUX2_SEL";
130"EEPROM_I2C_SCL";
131"UN$524$CONNUSB14PGH4FRATH$I495$CC2";
132"FT_USB_DM";
133"FT_USB_DP";
134"UN$524$CONNUSB14PGH4FRATH$I495$CC1";
135"FT_USB_DM";
136"FT_USB_DP";
137"FT4232_SPI_MISO";
138"FLASH_CS_N";
139"FPGA_PCA9546_I2C_SCL";
140"FLASH_CLK";
141"FLASH_DQ1_MISO";
142"R_FT4232_I2C_SDA_IN";
143"FPGA_FLASH_CLK";
144"FT4232_I2C_SDA";
145"FT4232_I2C_SCL";
146"FT4232_TDO_MISO";
%"GND_SG"
"1","(-12250,8600)","0","cls","I1";
;
HDL_POWER"SG"
CDS_LIB"cls"
CDS_LMAN_SYM_OUTLINE"0,0,100,-50"
BODY_TYPE"PLUMBING";
"SGND"40;
%"CAPACITOR"
"1","(-9650,7600)","1","passive","I10";
;
$LOCATION"C87"
CDS_LOCATION"C87"
$SEC"1"
CDS_SEC"1"
VALUE"18PF"
PACKAGE"0201"
CLS_PN"G104-0A180-FJ"
TOLERANCE"5%"
CDS_LMAN_SYM_OUTLINE"0,50,50,-50"
CDS_LIB"passive";
"2"
$PN"2"67;
"1"
$PN"1"10;
%"GND_SG"
"1","(-10950,11250)","0","cls","I102";
;
HDL_POWER"SG"
BODY_TYPE"PLUMBING"
CDS_LIB"cls"
CDS_LMAN_SYM_OUTLINE"0,0,100,-50";
"SGND"39;
%"RESISTOR"
"2","(-8350,8150)","0","passive","I106";
;
$LOCATION"R463"
CDS_LOCATION"R463"
$SEC"1"
CDS_SEC"1"
VALUE"12KOHM"
PACKAGE"0402"
TOLERANCE"1%"
CDS_LIB"passive"
CDS_LMAN_SYM_OUTLINE"-50,50,50,-100"
CLS_PN"G155-01202-01";
"1"
$PN"1"68;
"2"
$PN"2"34;
%"FERRITEBEAD"
"1","(-10050,11100)","0","passive","I118";
;
$LOCATION"L22"
CDS_LOCATION"L22"
$SEC"1"
CDS_SEC"1"
VALUE"600OHM"
DCR"1300MA 0.15OHM"
PACKAGE"0603"
CDS_LIB"passive"
CDS_LMAN_SYM_OUTLINE"0,0,200,-100"
CLS_PN"G191-10097-01"
TOLERANCE"25%";
"2"
$PN"2"114;
"1"
$PN"1"33;
%"GND_SG"
"1","(-9050,11300)","0","cls","I119";
;
HDL_POWER"SG"
BODY_TYPE"PLUMBING"
CDS_LIB"cls"
CDS_LMAN_SYM_OUTLINE"0,0,100,-50";
"SGND"38;
%"GND_SG"
"1","(-9050,10450)","0","cls","I120";
;
HDL_POWER"SG"
CDS_LMAN_SYM_OUTLINE"0,0,100,-50"
CDS_LIB"cls"
BODY_TYPE"PLUMBING";
"SGND"37;
%"RESISTOR"
"1","(-8600,9350)","0","passive","I121";
;
$LOCATION"R460"
CDS_LOCATION"R460"
$SEC"1"
CDS_SEC"1"
PACKAGE"0402"
VALUE"1KOHM"
CDS_LMAN_SYM_OUTLINE"-50,50,100,-50"
CDS_LIB"passive"
CLS_PN"G155-11001-01"
TOLERANCE"1%";
"1"
$PN"1"82;
"2"
$PN"2"119;
%"CAPACITOR"
"2","(-11450,10750)","0","passive","I123";
;
$LOCATION"C90"
CDS_LOCATION"C90"
$SEC"1"
CDS_SEC"1"
VALUE"4.7UF"
PACKAGE"0402"
TOLERANCE"20%"
CLS_PN"G105-0F475-BM"
CDS_LMAN_SYM_OUTLINE"-50,0,50,-50"
CDS_LIB"passive";
"2"
$PN"2"36;
"1"
$PN"1"81;
%"GND_SG"
"1","(-10950,10350)","0","cls","I124";
;
HDL_POWER"SG"
BODY_TYPE"PLUMBING"
CDS_LMAN_SYM_OUTLINE"0,0,100,-50"
CDS_LIB"cls";
"SGND"36;
%"FERRITEBEAD"
"1","(-10000,11900)","0","passive","I127";
;
$LOCATION"L4"
CDS_LOCATION"L4"
$SEC"1"
CDS_SEC"1"
DCR"1300MA 0.15OHM"
PACKAGE"0603"
VALUE"600OHM"
CDS_LMAN_SYM_OUTLINE"0,0,200,-100"
CDS_LIB"passive"
TOLERANCE"25%"
CLS_PN"G191-10097-01";
"2"
$PN"2"107;
"1"
$PN"1"33;
%"CAPACITOR"
"2","(-11450,11650)","0","passive","I128";
;
$LOCATION"C91"
CDS_LOCATION"C91"
$SEC"1"
CDS_SEC"1"
VOLTAGE"6.3V"
PACKAGE"0402"
VALUE"4.7UF"
CDS_LIB"passive"
CDS_LMAN_SYM_OUTLINE"-50,0,50,-50"
CLS_PN"G105-0F475-BM"
TOLERANCE"20%";
"2"
$PN"2"39;
"1"
$PN"1"33;
%"RESISTOR"
"1","(-5300,11150)","0","passive","I139";
;
$LOCATION"R470"
CDS_LOCATION"R470"
$SEC"1"
CDS_SEC"1"
VALUE"33OHM"
PACKAGE"0402"
TOLERANCE"1%"
CLS_PN"G155-133R0-01"
CDS_LMAN_SYM_OUTLINE"-50,50,100,-50"
CDS_LIB"passive";
"1"
$PN"1"60;
"2"
$PN"2"55;
%"RESISTOR"
"1","(-5300,11350)","0","passive","I140";
;
$LOCATION"R468"
CDS_LOCATION"R468"
$SEC"1"
CDS_SEC"1"
VALUE"33OHM"
PACKAGE"0402"
CDS_LMAN_SYM_OUTLINE"-50,50,100,-50"
CDS_LIB"passive"
TOLERANCE"1%"
CLS_PN"G155-133R0-01";
"1"
$PN"1"58;
"2"
$PN"2"56;
%"RESISTOR"
"1","(-5300,11450)","0","passive","I141";
;
$LOCATION"R467"
CDS_LOCATION"R467"
$SEC"1"
CDS_SEC"1"
PACKAGE"0402"
VALUE"33OHM"
CDS_LMAN_SYM_OUTLINE"-50,50,100,-50"
CDS_LIB"passive"
TOLERANCE"1%"
CLS_PN"G155-133R0-01";
"1"
$PN"1"62;
"2"
$PN"2"63;
%"RESISTOR"
"1","(-5300,11250)","0","passive","I142";
;
$LOCATION"R469"
CDS_LOCATION"R469"
$SEC"1"
CDS_SEC"1"
VALUE"33OHM"
PACKAGE"0402"
TOLERANCE"1%"
CLS_PN"G155-133R0-01"
CDS_LMAN_SYM_OUTLINE"-50,50,100,-50"
CDS_LIB"passive";
"1"
$PN"1"59;
"2"
$PN"2"146;
%"RESISTOR"
"2","(-4200,9200)","1","passive","I149";
;
$LOCATION"R480"
CDS_LOCATION"R480"
$SEC"1"
CDS_SEC"1"
PACKAGE"0402"
VALUE"100KOHM"
TOLERANCE"1%"
CDS_LIB"passive"
CDS_LMAN_SYM_OUTLINE"-50,50,50,-100"
CLS_PN"G155-11003-01";
"1"
$PN"1"97;
"2"
$PN"2"31;
%"RESISTOR"
"2","(-4200,9100)","1","passive","I150";
;
$LOCATION"R481"
CDS_LOCATION"R481"
$SEC"1"
CDS_SEC"1"
VALUE"100KOHM"
PACKAGE"0402"
TOLERANCE"1%"
CDS_LIB"passive"
CDS_LMAN_SYM_OUTLINE"-50,50,50,-100"
CLS_PN"G155-11003-01";
"1"
$PN"1"74;
"2"
$PN"2"31;
%"RESISTOR"
"1","(-5300,9650)","0","passive","I153";
;
$LOCATION"R353"
CDS_LOCATION"R353"
$SEC"1"
CDS_SEC"1"
PACKAGE"0402"
VALUE"100OHM"
TOLERANCE"1%"
CDS_LIB"passive"
CDS_LMAN_SYM_OUTLINE"-50,50,100,-50"
CLS_PN"G155-11000-01";
"1"
$PN"1"113;
"2"
$PN"2"97;
%"RESISTOR"
"1","(-5300,9550)","0","passive","I154";
;
$LOCATION"R352"
CDS_LOCATION"R352"
$SEC"1"
CDS_SEC"1"
VALUE"100OHM"
PACKAGE"0402"
TOLERANCE"1%"
CDS_LIB"passive"
CDS_LMAN_SYM_OUTLINE"-50,50,100,-50"
CLS_PN"G155-11000-01";
"1"
$PN"1"74;
"2"
$PN"2"109;
%"RESISTOR"
"1","(-5300,10450)","0","passive","I166";
;
$LOCATION"R472"
CDS_LOCATION"R472"
$SEC"1"
CDS_SEC"1"
PACKAGE"0402"
VALUE"0OHM"
CDS_LMAN_SYM_OUTLINE"-50,50,100,-50"
CDS_LIB"passive"
TOLERANCE"-"
CLS_PN"G155-100R0-J0";
"1"
$PN"1"53;
"2"
$PN"2"144;
%"RESISTOR"
"1","(-5300,10550)","0","passive","I169";
;
$LOCATION"R471"
CDS_LOCATION"R471"
$SEC"1"
CDS_SEC"1"
VALUE"0OHM"
PACKAGE"0402"
CDS_LIB"passive"
CDS_LMAN_SYM_OUTLINE"-50,50,100,-50"
TOLERANCE"-"
CLS_PN"G155-100R0-J0";
"1"
$PN"1"106;
"2"
$PN"2"145;
%"RESISTOR"
"1","(-5300,10350)","0","passive","I170";
;
$LOCATION"R473"
CDS_LOCATION"R473"
$SEC"1"
CDS_SEC"1"
PACKAGE"0402"
VALUE"0OHM"
CDS_LMAN_SYM_OUTLINE"-50,50,100,-50"
CDS_LIB"passive"
TOLERANCE"-"
CLS_PN"G155-100R0-J0";
"1"
$PN"1"142;
"2"
$PN"2"144;
%"G200_10283_01"
"1","(-2650,8850)","0","connector","I173";
;
$LOCATION"J10"
CDS_LOCATION"J10"
$SEC"1"
CDS_SEC"1"
CLS_PN"G200-10283-01"
PART_NUMBER"95278-101A10LF"
CDS_LIB"connector"
CDS_LMAN_SYM_OUTLINE"0,0,500,-1000";
"10"
$PN"10"76;
"9"
$PN"9"8;
"8"
$PN"8"80;
"7"
$PN"7"51;
"6"
$PN"6"79;
"5"
$PN"5"51;
"4"
$PN"4"78;
"3"
$PN"3"50;
"2"
$PN"2"77;
"1"
$PN"1"50;
%"RESISTOR"
"2","(-4200,9000)","1","passive","I184";
;
$LOCATION"R349"
CDS_LOCATION"R349"
$SEC"1"
CDS_SEC"1"
VALUE"100KOHM"
PACKAGE"0402"
TOLERANCE"1%"
CLS_PN"G155-11003-01"
CDS_LIB"passive"
CDS_LMAN_SYM_OUTLINE"-50,50,50,-100";
"1"
$PN"1"52;
"2"
$PN"2"31;
%"RESISTOR"
"1","(-5300,8750)","0","passive","I187";
;
$LOCATION"R131"
CDS_LOCATION"R131"
$SEC"1"
CDS_SEC"1"
PACKAGE"0402"
VALUE"100OHM"
CLS_PN"G155-11000-01"
TOLERANCE"1%"
CDS_LMAN_SYM_OUTLINE"-50,50,100,-50"
CDS_LIB"passive";
"1"
$PN"1"57;
"2"
$PN"2"50;
%"RESISTOR"
"1","(-5300,8650)","0","passive","I188";
;
$LOCATION"R132"
CDS_LOCATION"R132"
$SEC"1"
CDS_SEC"1"
PACKAGE"0402"
VALUE"100OHM"
TOLERANCE"1%"
CLS_PN"G155-11000-01"
CDS_LMAN_SYM_OUTLINE"-50,50,100,-50"
CDS_LIB"passive";
"1"
$PN"1"52;
"2"
$PN"2"51;
%"RESISTOR"
"2","(-4200,10100)","1","passive","I190";
;
$LOCATION"R478"
CDS_LOCATION"R478"
$SEC"1"
CDS_SEC"1"
PACKAGE"0402"
VALUE"100KOHM"
CLS_PN"G155-11003-01"
CDS_LMAN_SYM_OUTLINE"-50,50,50,-100"
CDS_LIB"passive"
TOLERANCE"1%";
"1"
$PN"1"145;
"2"
$PN"2"30;
%"RESISTOR"
"2","(-4200,10000)","1","passive","I191";
;
$LOCATION"R479"
CDS_LOCATION"R479"
$SEC"1"
CDS_SEC"1"
VALUE"100KOHM"
PACKAGE"0402"
CLS_PN"G155-11003-01"
CDS_LMAN_SYM_OUTLINE"-50,50,50,-100"
CDS_LIB"passive"
TOLERANCE"1%";
"1"
$PN"1"144;
"2"
$PN"2"30;
%"RESISTOR"
"2","(-5300,11600)","1","passive","I198";
;
$LOCATION"R466"
CDS_LOCATION"R466"
$SEC"1"
CDS_SEC"1"
VALUE"100KOHM"
PACKAGE"0402"
TOLERANCE"1%"
CLS_PN"G155-11003-01"
CDS_LMAN_SYM_OUTLINE"-50,50,50,-100"
CDS_LIB"passive";
"1"
$PN"1"59;
"2"
$PN"2"7;
%"CAT93C46VI_GT3_SOIC8"
"1","(-12050,7550)","2","memory","I200";
;
$LOCATION"U31"
CDS_LOCATION"U31"
$SEC"1"
CDS_SEC"1"
CLS_PN"G221-10075-01"
CDS_LIB"memory"
CDS_LMAN_SYM_OUTLINE"0,0,500,-500";
"NC"
$PN"7"0;
"ORG"
$PN"6"32;
"DO"
$PN"4"83;
"DI"
$PN"3"65;
"SK"
$PN"2"66;
"CS"
$PN"1"47;
%"CAT93C46VI_GT3_SOIC8"
"2","(-13700,7700)","0","memory","I201";
;
$LOCATION"U31"
CDS_LOCATION"U31"
$SEC"2"
CDS_SEC"2"
CLS_PN"G221-10075-01"
CDS_LMAN_SYM_OUTLINE"0,0,400,-500"
CDS_LIB"memory";
"GND"
$PN"5"35;
"VCC"
$PN"8"32;
%"GND_SG"
"1","(-13550,6850)","0","cls","I204";
;
HDL_POWER"SG"
BODY_TYPE"PLUMBING"
CDS_LIB"cls"
CDS_LMAN_SYM_OUTLINE"0,0,100,-50";
"SGND"35;
%"RESISTOR"
"1","(-12350,7950)","0","passive","I206";
;
$LOCATION"R447"
CDS_LOCATION"R447"
$SEC"1"
CDS_SEC"1"
VALUE"10KOHM"
PACKAGE"0402"
CLS_PN"G155-11002-01"
CDS_LIB"passive"
CDS_LMAN_SYM_OUTLINE"-50,50,100,-50"
TOLERANCE"1%";
"1"
$PN"1"32;
"2"
$PN"2"66;
%"RESISTOR"
"1","(-12350,8050)","0","passive","I207";
;
$LOCATION"R446"
CDS_LOCATION"R446"
$SEC"1"
CDS_SEC"1"
VALUE"10KOHM"
PACKAGE"0402"
TOLERANCE"1%"
CDS_LMAN_SYM_OUTLINE"-50,50,100,-50"
CDS_LIB"passive"
CLS_PN"G155-11002-01";
"1"
$PN"1"32;
"2"
$PN"2"47;
%"RESISTOR"
"2","(-13100,7550)","0","passive","I208";
;
$LOCATION"R444"
CDS_LOCATION"R444"
$SEC"1"
CDS_SEC"1"
PACKAGE"0402"
VALUE"10KOHM"
CLS_PN"G155-11002-01"
CDS_LIB"passive"
CDS_LMAN_SYM_OUTLINE"-50,50,50,-100"
TOLERANCE"1%";
"1"
$PN"1"32;
"2"
$PN"2"83;
%"RESISTOR"
"2","(-8950,8150)","0","passive","I23";
;
$LOCATION"R130"
CDS_LOCATION"R130"
$SEC"1"
CDS_SEC"1"
PACKAGE"0402"
VALUE"10KOHM"
CLS_PN"G155-11002-01"
CDS_LMAN_SYM_OUTLINE"-50,50,50,-100"
CDS_LIB"passive"
TOLERANCE"1%";
"1"
$PN"1"82;
"2"
$PN"2"34;
%"GND_SG"
"1","(-9000,7600)","0","cls","I25";
;
HDL_POWER"SG"
CDS_LIB"cls"
CDS_LMAN_SYM_OUTLINE"0,0,100,-50"
BODY_TYPE"PLUMBING";
"SGND"34;
%"RESISTOR"
"1","(-9300,9750)","0","passive","I26";
;
$LOCATION"R129"
CDS_LOCATION"R129"
$SEC"1"
CDS_SEC"1"
VALUE"0OHM"
PACKAGE"0402"
CLS_PN"G155-100R0-J0"
TOLERANCE"-"
CDS_LMAN_SYM_OUTLINE"-50,50,100,-50"
CDS_LIB"passive";
"1"
$PN"1"128;
"2"
$PN"2"105;
%"RESISTOR"
"2","(-9600,9350)","1","passive","I27";
;
$LOCATION"R18"
CDS_LOCATION"R18"
$SEC"1"
CDS_SEC"1"
PACKAGE"0402"
VALUE"4.7KOHM"
CDS_LMAN_SYM_OUTLINE"-50,50,50,-100"
CDS_LIB"passive"
TOLERANCE"1%"
CLS_PN"G155-14701-01";
"1"
$PN"1"22;
"2"
$PN"2"82;
%"RESISTOR"
"1","(-9300,9850)","0","passive","I28";
;
$LOCATION"R128"
CDS_LOCATION"R128"
$SEC"1"
CDS_SEC"1"
PACKAGE"0402"
VALUE"0OHM"
CLS_PN"G155-100R0-J0"
TOLERANCE"-"
CDS_LMAN_SYM_OUTLINE"-50,50,100,-50"
CDS_LIB"passive";
"1"
$PN"1"123;
"2"
$PN"2"99;
%"RESISTOR"
"2","(-10250,8450)","1","passive","I287";
;
$LOCATION"R455"
CDS_LOCATION"R455"
$SEC"1"
CDS_SEC"1"
VALUE"1MOHM"
NO_ASSY"TRUE"
PACKAGE"0402"
TOLERANCE"1%"
CLS_PN"G155-11004-01"
CDS_LMAN_SYM_OUTLINE"-50,50,50,-100"
CDS_LIB"passive";
"1"
$PN"1"46;
"2"
$PN"2"67;
%"GND_SG"
"1","(-3050,7800)","0","cls","I288";
;
HDL_POWER"SG"
CDS_LIB"cls"
CDS_LMAN_SYM_OUTLINE"0,0,100,-50"
BODY_TYPE"PLUMBING";
"SGND"8;
%"CL1001485A"
"1","(-11900,8900)","7","other","I3";
;
$LOCATION"U17"
CDS_LOCATION"U17"
$SEC"1"
CDS_SEC"1"
CLS_PN"G122-00019-01"
PART_NUMBER"SRV05-4ATCT"
CDS_LMAN_SYM_OUTLINE"0,0,450,-600"
CDS_LIB"other";
"6"
$PN"6"133;
"5"
$PN"5"22;
"4"
$PN"4"132;
"3"
$PN"3"0;
"2"
$PN"2"40;
"1"
$PN"1"0;
%"RESISTOR"
"1","(-11950,6850)","2","passive","I310";
;
$LOCATION"R454"
CDS_LOCATION"R454"
$SEC"1"
CDS_SEC"1"
PACKAGE"0402"
VALUE"2.2KOHM"
TOLERANCE"1%"
CDS_LMAN_SYM_OUTLINE"-50,50,100,-50"
CDS_LIB"passive"
CLS_PN"G155-12201-01";
"1"
$PN"1"65;
"2"
$PN"2"83;
%"TP_PIONT"
"1","(-6250,10750)","0","cls","I311";
;
$LOCATION"TP5"
CDS_LOCATION"TP5"
$SEC"1"
CDS_SEC"1"
BOM_IGNORE"TRUE"
JEDEC_TYPE"TP010CT020B030_PTH"
CDS_LMAN_SYM_OUTLINE"-50,50,50,-50"
CDS_LIB"cls";
"1 \B"
$PN"1"102;
%"TP_PIONT"
"1","(-6250,10250)","0","cls","I312";
;
$LOCATION"TP6"
CDS_LOCATION"TP6"
$SEC"1"
CDS_SEC"1"
BOM_IGNORE"TRUE"
JEDEC_TYPE"TP010CT020B030_PTH"
CDS_LMAN_SYM_OUTLINE"-50,50,50,-50"
CDS_LIB"cls";
"1 \B"
$PN"1"103;
%"TP_PIONT"
"1","(-6250,10150)","0","cls","I313";
;
$LOCATION"TP7"
CDS_LOCATION"TP7"
$SEC"1"
CDS_SEC"1"
BOM_IGNORE"TRUE"
JEDEC_TYPE"TP010CT020B030_PTH"
CDS_LMAN_SYM_OUTLINE"-50,50,50,-50"
CDS_LIB"cls";
"1 \B"
$PN"1"104;
%"TP_PIONT"
"1","(-6250,9950)","0","cls","I314";
;
$LOCATION"TP9"
CDS_LOCATION"TP9"
$SEC"1"
CDS_SEC"1"
BOM_IGNORE"TRUE"
JEDEC_TYPE"TP010CT020B030_PTH"
CDS_LMAN_SYM_OUTLINE"-50,50,50,-50"
CDS_LIB"cls";
"1 \B"
$PN"1"118;
%"TP_PIONT"
"1","(-6250,10050)","0","cls","I315";
;
$LOCATION"TP8"
CDS_LOCATION"TP8"
$SEC"1"
CDS_SEC"1"
CDS_LIB"cls"
CDS_LMAN_SYM_OUTLINE"-50,50,50,-50"
JEDEC_TYPE"TP010CT020B030_PTH"
BOM_IGNORE"TRUE";
"1 \B"
$PN"1"54;
%"TP_PIONT"
"1","(-6250,9850)","0","cls","I316";
;
$LOCATION"TP10"
CDS_LOCATION"TP10"
$SEC"1"
CDS_SEC"1"
CDS_LIB"cls"
CDS_LMAN_SYM_OUTLINE"-50,50,50,-50"
JEDEC_TYPE"TP010CT020B030_PTH"
BOM_IGNORE"TRUE";
"1 \B"
$PN"1"117;
%"VCC"
"1","(-11500,12000)","0","cls","I359";
;
HDL_POWER"XP3R3V_FT4232"
VOLTAGE"3.3V"
BODY_TYPE"PLUMBING"
CDS_LMAN_SYM_OUTLINE"-250,250,250,-250"
CDS_LIB"cls";
"$PIN0"33;
%"VCC"
"1","(-14200,8200)","0","cls","I360";
;
HDL_POWER"XP3R3V_FT4232"
VOLTAGE"3.3V"
BODY_TYPE"PLUMBING"
CDS_LMAN_SYM_OUTLINE"-250,250,250,-250"
CDS_LIB"cls";
"$PIN0"32;
%"VCC"
"1","(-3200,9150)","0","cls","I362";
;
VOLTAGE"3.3V"
HDL_POWER"XP3R3V_FT4232"
BODY_TYPE"PLUMBING"
CDS_LMAN_SYM_OUTLINE"-250,250,250,-250"
CDS_LIB"cls";
"$PIN0"31;
%"VCC"
"1","(-3300,10100)","0","cls","I363";
;
HDL_POWER"XP3R3V_FT4232"
VOLTAGE"3.3V"
CDS_LIB"cls"
CDS_LMAN_SYM_OUTLINE"-250,250,250,-250"
BODY_TYPE"PLUMBING";
"$PIN0"30;
%"VCC"
"1","(-4550,11750)","0","cls","I364";
;
HDL_POWER"XP3R3V_FT4232"
VOLTAGE"3.3V"
CDS_LIB"cls"
CDS_LMAN_SYM_OUTLINE"-250,250,250,-250"
BODY_TYPE"PLUMBING";
"$PIN0"7;
%"VCC"
"1","(-8250,11950)","0","cls","I365";
;
VOLTAGE"3.3V"
HDL_POWER"XP3R3V_FT4232"
BODY_TYPE"PLUMBING"
CDS_LMAN_SYM_OUTLINE"-250,250,250,-250"
CDS_LIB"cls";
"$PIN0"29;
%"RESISTOR"
"1","(-9600,9500)","0","passive","I368";
;
$LOCATION"R456"
CDS_LOCATION"R456"
$SEC"1"
CDS_SEC"1"
VALUE"100OHM"
PACKAGE"0402"
CDS_LIB"passive"
CDS_LMAN_SYM_OUTLINE"-50,50,100,-50"
CLS_PN"G155-11000-01"
TOLERANCE"1%";
"1"
$PN"1"98;
"2"
$PN"2"82;
%"CAPACITOR"
"2","(-9000,10800)","2","passive","I373";
;
$LOCATION"C101"
CDS_LOCATION"C101"
$SEC"1"
CDS_SEC"1"
VALUE"0.1UF"
VOLTAGE"25V"
PACKAGE"0402"
CDS_LIB"passive"
CDS_LMAN_SYM_OUTLINE"-50,0,50,-50"
CLS_PN"G105-0B104-EK"
TOLERANCE"10%";
"2"
$PN"2"37;
"1"
$PN"1"114;
%"CAPACITOR"
"2","(-9000,11600)","2","passive","I374";
;
$LOCATION"C100"
CDS_LOCATION"C100"
$SEC"1"
CDS_SEC"1"
VALUE"0.1UF"
VOLTAGE"25V"
PACKAGE"0402"
TOLERANCE"10%"
CLS_PN"G105-0B104-EK"
CDS_LMAN_SYM_OUTLINE"-50,0,50,-50"
CDS_LIB"passive";
"2"
$PN"2"38;
"1"
$PN"1"107;
%"CAPACITOR"
"2","(-10900,11600)","2","passive","I375";
;
$LOCATION"C95"
CDS_LOCATION"C95"
$SEC"1"
CDS_SEC"1"
VOLTAGE"25V"
VALUE"0.1UF"
PACKAGE"0402"
CDS_LIB"passive"
CDS_LMAN_SYM_OUTLINE"-50,0,50,-50"
CLS_PN"G105-0B104-EK"
TOLERANCE"10%";
"2"
$PN"2"39;
"1"
$PN"1"33;
%"CAPACITOR"
"2","(-10900,10750)","2","passive","I376";
;
$LOCATION"C96"
CDS_LOCATION"C96"
$SEC"1"
CDS_SEC"1"
VALUE"0.1UF"
VOLTAGE"25V"
PACKAGE"0402"
CDS_LIB"passive"
CDS_LMAN_SYM_OUTLINE"-50,0,50,-50"
CLS_PN"G105-0B104-EK"
TOLERANCE"10%";
"2"
$PN"2"36;
"1"
$PN"1"81;
%"CAPACITOR"
"2","(-11700,9150)","2","passive","I377";
;
$LOCATION"C94"
CDS_LOCATION"C94"
$SEC"1"
CDS_SEC"1"
PACKAGE"0402"
VALUE"0.1UF"
VOLTAGE"25V"
TOLERANCE"10%"
CLS_PN"G105-0B104-EK"
CDS_LMAN_SYM_OUTLINE"-50,0,50,-50"
CDS_LIB"passive";
"2"
$PN"2"40;
"1"
$PN"1"22;
%"CAPACITOR"
"2","(-14150,7550)","2","passive","I378";
;
$LOCATION"C88"
CDS_LOCATION"C88"
$SEC"1"
CDS_SEC"1"
VOLTAGE"25V"
VALUE"0.1UF"
PACKAGE"0402"
TOLERANCE"10%"
CLS_PN"G105-0B104-EK"
CDS_LMAN_SYM_OUTLINE"-50,0,50,-50"
CDS_LIB"passive";
"2"
$PN"2"35;
"1"
$PN"1"32;
%"CAPACITOR"
"2","(-9500,11600)","0","passive","I379";
;
$LOCATION"C98"
CDS_LOCATION"C98"
$SEC"1"
CDS_SEC"1"
VOLTAGE"6.3V"
PACKAGE"0402"
VALUE"4.7UF"
CDS_LIB"passive"
CDS_LMAN_SYM_OUTLINE"-50,0,50,-50"
TOLERANCE"20%"
CLS_PN"G105-0F475-BM";
"2"
$PN"2"38;
"1"
$PN"1"107;
%"CAPACITOR"
"2","(-9500,10800)","0","passive","I380";
;
$LOCATION"C99"
CDS_LOCATION"C99"
$SEC"1"
CDS_SEC"1"
VOLTAGE"6.3V"
PACKAGE"0402"
VALUE"4.7UF"
CDS_LIB"passive"
CDS_LMAN_SYM_OUTLINE"-50,0,50,-50"
TOLERANCE"20%"
CLS_PN"G105-0F475-BM";
"2"
$PN"2"37;
"1"
$PN"1"114;
%"VCC"
"1","(-12600,10800)","0","cls","I386";
;
VOLTAGE"5V"
HDL_POWER"XP5R0V_FT4232"
CDS_LIB"cls"
CDS_LMAN_SYM_OUTLINE"-250,250,250,-250"
BODY_TYPE"PLUMBING";
"$PIN0"28;
%"GND_SG"
"1","(-14050,8750)","0","cls","I393";
;
HDL_POWER"SG"
BODY_TYPE"PLUMBING"
CDS_LMAN_SYM_OUTLINE"0,0,100,-50"
CDS_LIB"cls";
"SGND"27;
%"VCC"
"1","(-14200,10800)","0","cls","I394";
;
HDL_POWER"XP5R0V_FT4232"
VOLTAGE"5V"
CDS_LIB"cls"
CDS_LMAN_SYM_OUTLINE"-250,250,250,-250"
BODY_TYPE"PLUMBING";
"$PIN0"26;
%"RESISTOR"
"2","(-12350,10050)","1","passive","I395";
;
$LOCATION"R445"
CDS_LOCATION"R445"
$SEC"1"
CDS_SEC"1"
VALUE"5.1KOHM"
PACKAGE"0402"
CLS_PN"G155-05101-01"
TOLERANCE"1%"
CDS_LMAN_SYM_OUTLINE"-50,50,50,-100"
CDS_LIB"passive";
"1"
$PN"1"131;
"2"
$PN"2"4;
%"TS3A5018PWR_TSSOP16"
"1","(-7700,6000)","0","stdlogic","I400";
;
$LOCATION"U38"
CDS_LOCATION"U38"
$SEC"1"
CDS_SEC"1"
PART_NUMBER"TS3A5018PWR"
CLS_PN"G220-10324-01"
CDS_LMAN_SYM_OUTLINE"0,0,600,-1500"
CDS_LIB"stdlogic";
"NO4"
$PN"13"45;
"NO3"
$PN"10"137;
"NO2"
$PN"6"49;
"NO1"
$PN"3"48;
"NC4"
$PN"14"69;
"NC3"
$PN"11"126;
"NC2"
$PN"5"121;
"NC1"
$PN"2"143;
"IN"
$PN"1"93;
"EN* \B"
$PN"15"94;
"COM4"
$PN"12"138;
"COM3"
$PN"9"141;
"COM2"
$PN"7"75;
"COM1"
$PN"4"140;
%"NLASB3157DFT2G_SC88"
"1","(-7100,4000)","2","interface","I407";
;
$LOCATION"U39"
CDS_LOCATION"U39"
$SEC"1"
CDS_SEC"1"
CLS_PN"G223-10187-01"
CDS_LIB"interface"
CDS_LMAN_SYM_OUTLINE"0,0,600,-400";
"SELECT"
$PN"6"93;
"B1"
$PN"1"0;
"B0"
$PN"3"101;
"A"
$PN"4"95;
%"NLASB3157DFT2G_SC88"
"1","(-7100,3350)","2","interface","I408";
;
$LOCATION"U40"
CDS_LOCATION"U40"
$SEC"1"
CDS_SEC"1"
CLS_PN"G223-10187-01"
CDS_LIB"interface"
CDS_LMAN_SYM_OUTLINE"0,0,600,-400";
"SELECT"
$PN"6"93;
"B1"
$PN"1"0;
"B0"
$PN"3"100;
"A"
$PN"4"120;
%"RESISTOR"
"1","(-8550,4700)","0","passive","I411";
;
$LOCATION"R461"
CDS_LOCATION"R461"
$SEC"1"
CDS_SEC"1"
VALUE"33OHM"
NO_ASSY"TRUE"
PACKAGE"0402"
TOLERANCE"1%"
CDS_LIB"passive"
CDS_LMAN_SYM_OUTLINE"-50,50,100,-50"
CLS_PN"G155-133R0-01";
"1"
$PN"1"129;
"2"
$PN"2"93;
%"RESISTOR"
"1","(-8550,4600)","0","passive","I412";
;
$LOCATION"R462"
CDS_LOCATION"R462"
$SEC"1"
CDS_SEC"1"
VALUE"33OHM"
PACKAGE"0402"
CLS_PN"G155-133R0-01"
CDS_LMAN_SYM_OUTLINE"-50,50,100,-50"
CDS_LIB"passive"
TOLERANCE"1%";
"1"
$PN"1"96;
"2"
$PN"2"93;
%"RESISTOR"
"1","(-12000,4700)","0","passive","I423";
;
$LOCATION"R448"
CDS_LOCATION"R448"
$SEC"1"
CDS_SEC"1"
VALUE"33OHM"
NO_ASSY"TRUE"
PACKAGE"0402"
CDS_LIB"passive"
CDS_LMAN_SYM_OUTLINE"-50,50,100,-50"
CLS_PN"G155-133R0-01"
TOLERANCE"1%";
"1"
$PN"1"42;
"2"
$PN"2"70;
%"RESISTOR"
"1","(-12000,4600)","0","passive","I424";
;
$LOCATION"R449"
CDS_LOCATION"R449"
$SEC"1"
CDS_SEC"1"
VALUE"33OHM"
PACKAGE"0402"
CDS_LIB"passive"
CDS_LMAN_SYM_OUTLINE"-50,50,100,-50"
CLS_PN"G155-133R0-01"
TOLERANCE"1%";
"1"
$PN"1"42;
"2"
$PN"2"71;
%"TS3A5018PWR_TSSOP16"
"1","(-12650,6000)","2","stdlogic","I425";
;
$LOCATION"U30"
CDS_LOCATION"U30"
$SEC"1"
CDS_SEC"1"
PART_NUMBER"TS3A5018PWR"
CLS_PN"G220-10324-01"
CDS_LIB"stdlogic"
CDS_LMAN_SYM_OUTLINE"0,0,600,-1500";
"NO4"
$PN"13"45;
"NO3"
$PN"10"137;
"NO2"
$PN"6"49;
"NO1"
$PN"3"48;
"NC4"
$PN"14"124;
"NC3"
$PN"11"122;
"NC2"
$PN"5"115;
"NC1"
$PN"2"116;
"IN"
$PN"1"42;
"EN* \B"
$PN"15"41;
"COM4"
$PN"12"88;
"COM3"
$PN"9"89;
"COM2"
$PN"7"90;
"COM1"
$PN"4"91;
%"RESISTOR"
"2","(-8800,4100)","1","passive","I430";
;
$LOCATION"R458"
CDS_LOCATION"R458"
$SEC"1"
CDS_SEC"1"
VALUE"1KOHM"
PACKAGE"0402"
CLS_PN"G155-11001-01"
TOLERANCE"1%"
CDS_LMAN_SYM_OUTLINE"-50,50,50,-100"
CDS_LIB"passive";
"1"
$PN"1"25;
"2"
$PN"2"93;
%"RESISTOR"
"2","(-8800,4200)","1","passive","I431";
;
$LOCATION"R457"
CDS_LOCATION"R457"
$SEC"1"
CDS_SEC"1"
VALUE"4.7KOHM"
PACKAGE"0402"
NO_ASSY"TRUE"
CDS_LIB"passive"
CDS_LMAN_SYM_OUTLINE"-50,50,50,-100"
CLS_PN"G155-14701-01"
TOLERANCE"1%";
"1"
$PN"1"6;
"2"
$PN"2"93;
%"RESISTOR"
"2","(-8800,4000)","1","passive","I432";
;
$LOCATION"R459"
CDS_LOCATION"R459"
$SEC"1"
CDS_SEC"1"
VALUE"1KOHM"
PACKAGE"0402"
CLS_PN"G155-11001-01"
TOLERANCE"1%"
CDS_LMAN_SYM_OUTLINE"-50,50,50,-100"
CDS_LIB"passive";
"1"
$PN"1"25;
"2"
$PN"2"94;
%"VCC"
"1","(-9300,4300)","0","cls","I434";
;
VOLTAGE"3.3V"
HDL_POWER"XP3R3V_FPGA"
BODY_TYPE"PLUMBING"
CDS_LIB"cls"
CDS_LMAN_SYM_OUTLINE"-250,250,250,-250";
"$PIN0"6;
%"GND_SG"
"1","(-9250,3900)","0","cls","I435";
;
VOLTAGE"0"
HDL_POWER"SG"
CDS_LMAN_SYM_OUTLINE"0,0,100,-50"
CDS_LIB"cls"
BODY_TYPE"PLUMBING";
"SGND"25;
%"VCC"
"1","(-11350,4300)","0","cls","I437";
;
VOLTAGE"3.3V"
HDL_POWER"XP3R3V_FPGA"
CDS_LIB"cls"
CDS_LMAN_SYM_OUTLINE"-250,250,250,-250"
BODY_TYPE"PLUMBING";
"$PIN0"24;
%"GND_SG"
"1","(-11400,3750)","0","cls","I438";
;
HDL_POWER"SG"
VOLTAGE"0"
BODY_TYPE"PLUMBING"
CDS_LIB"cls"
CDS_LMAN_SYM_OUTLINE"0,0,100,-50";
"SGND"23;
%"VCC"
"1","(-11350,9950)","0","cls","I44";
;
VOLTAGE"5V"
HDL_POWER"XP5R0V_FT4232"
BODY_TYPE"PLUMBING"
CDS_LMAN_SYM_OUTLINE"-250,250,250,-250"
CDS_LIB"cls";
"$PIN0"22;
%"RESISTOR"
"2","(-12000,4200)","1","passive","I440";
;
$LOCATION"R450"
CDS_LOCATION"R450"
$SEC"1"
CDS_SEC"1"
PACKAGE"0402"
VALUE"4.7KOHM"
CDS_LIB"passive"
CDS_LMAN_SYM_OUTLINE"-50,50,50,-100"
CLS_PN"G155-14701-01"
TOLERANCE"1%";
"1"
$PN"1"42;
"2"
$PN"2"24;
%"RESISTOR"
"2","(-12000,4100)","1","passive","I441";
;
$LOCATION"R451"
CDS_LOCATION"R451"
$SEC"1"
CDS_SEC"1"
PACKAGE"0402"
NO_ASSY"TRUE"
VALUE"1KOHM"
CDS_LIB"passive"
CDS_LMAN_SYM_OUTLINE"-50,50,50,-100"
TOLERANCE"1%"
CLS_PN"G155-11001-01";
"1"
$PN"1"42;
"2"
$PN"2"23;
%"RESISTOR"
"2","(-12000,3900)","1","passive","I442";
;
$LOCATION"R453"
CDS_LOCATION"R453"
$SEC"1"
CDS_SEC"1"
PACKAGE"0402"
VALUE"1KOHM"
NO_ASSY"TRUE"
CDS_LIB"passive"
CDS_LMAN_SYM_OUTLINE"-50,50,50,-100"
TOLERANCE"1%"
CLS_PN"G155-11001-01";
"1"
$PN"1"41;
"2"
$PN"2"23;
%"RESISTOR"
"2","(-12000,4000)","1","passive","I443";
;
$LOCATION"R452"
CDS_LOCATION"R452"
$SEC"1"
CDS_SEC"1"
VALUE"4.7KOHM"
PACKAGE"0402"
TOLERANCE"1%"
CLS_PN"G155-14701-01"
CDS_LMAN_SYM_OUTLINE"-50,50,50,-100"
CDS_LIB"passive";
"1"
$PN"1"41;
"2"
$PN"2"24;
%"GND_SG"
"1","(-12700,3750)","0","cls","I444";
;
HDL_POWER"SG"
VOLTAGE"0"
BODY_TYPE"PLUMBING"
CDS_LMAN_SYM_OUTLINE"0,0,100,-50"
CDS_LIB"cls";
"SGND"21;
%"POWERMOS_3P_NCH_V1"
"1","(-13000,4100)","0","discrete","I445";
;
$LOCATION"Q1"
CDS_LOCATION"Q1"
$SEC"1"
CDS_SEC"1"
CLS_PN"G121-10200-01"
PART_NUMBER"BSS138"
CDS_LMAN_SYM_OUTLINE"-200,200,200,-200"
CDS_LIB"discrete";
"D"
$PN"3"41;
"G"
$PN"1"43;
"S"
$PN"2"21;
%"RESISTOR"
"1","(-13200,3450)","0","passive","I446";
;
$LOCATION"R443"
CDS_LOCATION"R443"
$SEC"1"
CDS_SEC"1"
VALUE"100OHM"
PACKAGE"0402"
NO_ASSY"TRUE"
CDS_LIB"passive"
CDS_LMAN_SYM_OUTLINE"-50,50,100,-50"
CLS_PN"G155-11000-01"
TOLERANCE"1%";
"1"
$PN"1"43;
"2"
$PN"2"44;
%"TS3A5018PWR_TSSOP16"
"1","(-2100,5700)","0","stdlogic","I448";
;
$LOCATION"U37"
CDS_LOCATION"U37"
$SEC"1"
CDS_SEC"1"
CLS_PN"G220-10324-01"
PART_NUMBER"TS3A5018PWR"
CDS_LIB"stdlogic"
CDS_LMAN_SYM_OUTLINE"0,0,600,-1500";
"NO4"
$PN"13"108;
"NO3"
$PN"10"73;
"NO2"
$PN"6"108;
"NO1"
$PN"3"73;
"NC4"
$PN"14"72;
"NC3"
$PN"11"92;
"NC2"
$PN"5"139;
"NC1"
$PN"2"125;
"IN"
$PN"1"84;
"EN* \B"
$PN"15"87;
"COM4"
$PN"12"130;
"COM3"
$PN"9"110;
"COM2"
$PN"7"111;
"COM1"
$PN"4"127;
%"RESISTOR"
"1","(-3000,4400)","0","passive","I459";
;
$LOCATION"R485"
CDS_LOCATION"R485"
$SEC"1"
CDS_SEC"1"
PACKAGE"0402"
NO_ASSY"TRUE"
VALUE"33OHM"
TOLERANCE"1%"
CDS_LIB"passive"
CDS_LMAN_SYM_OUTLINE"-50,50,100,-50"
CLS_PN"G155-133R0-01";
"1"
$PN"1"85;
"2"
$PN"2"84;
%"RESISTOR"
"1","(-3000,4300)","0","passive","I460";
;
$LOCATION"R486"
CDS_LOCATION"R486"
$SEC"1"
CDS_SEC"1"
PACKAGE"0402"
VALUE"33OHM"
CLS_PN"G155-133R0-01"
CDS_LMAN_SYM_OUTLINE"-50,50,100,-50"
CDS_LIB"passive"
TOLERANCE"1%";
"1"
$PN"1"86;
"2"
$PN"2"84;
%"VCC"
"1","(-3650,4000)","0","cls","I461";
;
VOLTAGE"3.3V"
HDL_POWER"XP3R3V_FPGA"
CDS_LMAN_SYM_OUTLINE"-250,250,250,-250"
CDS_LIB"cls"
BODY_TYPE"PLUMBING";
"$PIN0"5;
%"RESISTOR"
"2","(-3150,3750)","1","passive","I462";
;
$LOCATION"R483"
CDS_LOCATION"R483"
$SEC"1"
CDS_SEC"1"
VALUE"1KOHM"
PACKAGE"0402"
CLS_PN"G155-11001-01"
TOLERANCE"1%"
CDS_LMAN_SYM_OUTLINE"-50,50,50,-100"
CDS_LIB"passive";
"1"
$PN"1"20;
"2"
$PN"2"84;
%"RESISTOR"
"2","(-3150,3650)","1","passive","I463";
;
$LOCATION"R484"
CDS_LOCATION"R484"
$SEC"1"
CDS_SEC"1"
VALUE"1KOHM"
PACKAGE"0402"
CDS_LIB"passive"
CDS_LMAN_SYM_OUTLINE"-50,50,50,-100"
TOLERANCE"1%"
CLS_PN"G155-11001-01";
"1"
$PN"1"20;
"2"
$PN"2"87;
%"RESISTOR"
"2","(-3150,3850)","1","passive","I464";
;
$LOCATION"R482"
CDS_LOCATION"R482"
$SEC"1"
CDS_SEC"1"
VALUE"4.7KOHM"
NO_ASSY"TRUE"
PACKAGE"0402"
CDS_LIB"passive"
CDS_LMAN_SYM_OUTLINE"-50,50,50,-100"
CLS_PN"G155-14701-01"
TOLERANCE"1%";
"1"
$PN"1"5;
"2"
$PN"2"84;
%"GND_SG"
"1","(-3650,3500)","0","cls","I465";
;
HDL_POWER"SG"
VOLTAGE"0"
BODY_TYPE"PLUMBING"
CDS_LIB"cls"
CDS_LMAN_SYM_OUTLINE"0,0,100,-50";
"SGND"20;
%"RESISTOR"
"2","(-4500,5550)","1","passive","I466";
;
$LOCATION"R474"
CDS_LOCATION"R474"
$SEC"1"
CDS_SEC"1"
PACKAGE"0402"
VALUE"100KOHM"
CLS_PN"G155-11003-01"
CDS_LMAN_SYM_OUTLINE"-50,50,50,-100"
CDS_LIB"passive"
TOLERANCE"1%";
"1"
$PN"1"19;
"2"
$PN"2"125;
%"RESISTOR"
"2","(-4500,5250)","1","passive","I467";
;
$LOCATION"R475"
CDS_LOCATION"R475"
$SEC"1"
CDS_SEC"1"
VALUE"100KOHM"
PACKAGE"0402"
TOLERANCE"1%"
CDS_LIB"passive"
CDS_LMAN_SYM_OUTLINE"-50,50,50,-100"
CLS_PN"G155-11003-01";
"1"
$PN"1"19;
"2"
$PN"2"139;
%"RESISTOR"
"2","(-4500,4950)","1","passive","I468";
;
$LOCATION"R476"
CDS_LOCATION"R476"
$SEC"1"
CDS_SEC"1"
PACKAGE"0402"
VALUE"100KOHM"
TOLERANCE"1%"
CDS_LIB"passive"
CDS_LMAN_SYM_OUTLINE"-50,50,50,-100"
CLS_PN"G155-11003-01";
"1"
$PN"1"19;
"2"
$PN"2"92;
%"RESISTOR"
"2","(-4500,4650)","1","passive","I469";
;
$LOCATION"R477"
CDS_LOCATION"R477"
$SEC"1"
CDS_SEC"1"
PACKAGE"0402"
VALUE"100KOHM"
CLS_PN"G155-11003-01"
CDS_LMAN_SYM_OUTLINE"-50,50,50,-100"
CDS_LIB"passive"
TOLERANCE"1%";
"1"
$PN"1"19;
"2"
$PN"2"72;
%"VCC"
"1","(-5000,5750)","0","cls","I470";
;
VOLTAGE"3.3V"
HDL_POWER"XP3R3V_FPGA"
BODY_TYPE"PLUMBING"
CDS_LMAN_SYM_OUTLINE"-250,250,250,-250"
CDS_LIB"cls";
"$PIN0"19;
%"TS3A5018PWR_TSSOP16"
"2","(-13850,2750)","0","stdlogic","I473";
;
$LOCATION"U30"
CDS_LOCATION"U30"
$SEC"2"
CDS_SEC"2"
CLS_PN"G220-10324-01"
CDS_LIB"stdlogic"
CDS_LMAN_SYM_OUTLINE"0,0,400,-500";
"V_P"
$PN"16"17;
"GND"
$PN"8"16;
%"CAPACITOR"
"2","(-13200,2550)","2","passive","I474";
;
$LOCATION"C89"
CDS_LOCATION"C89"
$SEC"1"
CDS_SEC"1"
VOLTAGE"25V"
PACKAGE"0402"
VALUE"0.1UF"
CDS_LMAN_SYM_OUTLINE"-50,0,50,-50"
CDS_LIB"passive"
CLS_PN"G105-0B104-EK"
TOLERANCE"10%";
"2"
$PN"2"16;
"1"
$PN"1"17;
%"GND_SG"
"1","(-12400,2000)","0","cls","I475";
;
HDL_POWER"SG"
BODY_TYPE"PLUMBING"
CDS_LIB"cls"
CDS_LMAN_SYM_OUTLINE"0,0,100,-50";
"SGND"18;
%"CAPACITOR"
"2","(-11900,2550)","2","passive","I476";
;
$LOCATION"C92"
CDS_LOCATION"C92"
$SEC"1"
CDS_SEC"1"
PACKAGE"0402"
VALUE"0.1UF"
VOLTAGE"25V"
CDS_LIB"passive"
CDS_LMAN_SYM_OUTLINE"-50,0,50,-50"
TOLERANCE"10%"
CLS_PN"G105-0B104-EK";
"2"
$PN"2"18;
"1"
$PN"1"17;
%"TS3A5018PWR_TSSOP16"
"2","(-12550,2750)","0","stdlogic","I478";
;
$LOCATION"U37"
CDS_LOCATION"U37"
$SEC"2"
CDS_SEC"2"
CLS_PN"G220-10324-01"
CDS_LIB"stdlogic"
CDS_LMAN_SYM_OUTLINE"0,0,400,-500";
"V_P"
$PN"16"17;
"GND"
$PN"8"18;
%"VCC"
"1","(-13700,3000)","0","cls","I479";
;
VOLTAGE"3.3V"
HDL_POWER"XP3R3V_FPGA"
CDS_LMAN_SYM_OUTLINE"-250,250,250,-250"
CDS_LIB"cls"
BODY_TYPE"PLUMBING";
"$PIN0"17;
%"GND_SG"
"1","(-13700,2000)","0","cls","I480";
;
HDL_POWER"SG"
CDS_LIB"cls"
CDS_LMAN_SYM_OUTLINE"0,0,100,-50"
BODY_TYPE"PLUMBING";
"SGND"16;
%"TS3A5018PWR_TSSOP16"
"2","(-11300,2750)","0","stdlogic","I481";
;
$LOCATION"U38"
CDS_LOCATION"U38"
$SEC"2"
CDS_SEC"2"
CLS_PN"G220-10324-01"
CDS_LMAN_SYM_OUTLINE"0,0,400,-500"
CDS_LIB"stdlogic";
"V_P"
$PN"16"17;
"GND"
$PN"8"15;
%"CAPACITOR"
"2","(-10650,2550)","2","passive","I482";
;
$LOCATION"C97"
CDS_LOCATION"C97"
$SEC"1"
CDS_SEC"1"
VALUE"0.1UF"
PACKAGE"0402"
VOLTAGE"25V"
CDS_LIB"passive"
CDS_LMAN_SYM_OUTLINE"-50,0,50,-50"
TOLERANCE"10%"
CLS_PN"G105-0B104-EK";
"2"
$PN"2"15;
"1"
$PN"1"17;
%"GND_SG"
"1","(-11150,2000)","0","cls","I484";
;
HDL_POWER"SG"
BODY_TYPE"PLUMBING"
CDS_LMAN_SYM_OUTLINE"0,0,100,-50"
CDS_LIB"cls";
"SGND"15;
%"NLASB3157DFT2G_SC88"
"2","(-3650,2750)","0","interface","I485";
;
$LOCATION"U39"
CDS_LOCATION"U39"
$SEC"2"
CDS_SEC"2"
CLS_PN"G223-10187-01"
CDS_LMAN_SYM_OUTLINE"0,0,400,-500"
CDS_LIB"interface";
"VCC"
$PN"5"14;
"GND"
$PN"2"13;
%"CAPACITOR"
"2","(-3000,2550)","2","passive","I486";
;
$LOCATION"C123"
CDS_LOCATION"C123"
$SEC"1"
CDS_SEC"1"
VALUE"0.1UF"
PACKAGE"0402"
VOLTAGE"25V"
CDS_LIB"passive"
CDS_LMAN_SYM_OUTLINE"-50,0,50,-50"
CLS_PN"G105-0B104-EK"
TOLERANCE"10%";
"2"
$PN"2"13;
"1"
$PN"1"14;
%"VCC"
"1","(-3500,3000)","0","cls","I487";
;
HDL_POWER"XP3R3V_FPGA"
VOLTAGE"3.3V"
CDS_LIB"cls"
CDS_LMAN_SYM_OUTLINE"-250,250,250,-250"
BODY_TYPE"PLUMBING";
"$PIN0"14;
%"GND_SG"
"1","(-3500,2000)","0","cls","I488";
;
HDL_POWER"SG"
CDS_LIB"cls"
CDS_LMAN_SYM_OUTLINE"0,0,100,-50"
BODY_TYPE"PLUMBING";
"SGND"13;
%"VCC"
"1","(-4850,3000)","0","cls","I489";
;
HDL_POWER"XP3R3V_FPGA"
VOLTAGE"3.3V"
CDS_LIB"cls"
CDS_LMAN_SYM_OUTLINE"-250,250,250,-250"
BODY_TYPE"PLUMBING";
"$PIN0"12;
%"CAPACITOR"
"2","(-4350,2550)","2","passive","I490";
;
$LOCATION"C102"
CDS_LOCATION"C102"
$SEC"1"
CDS_SEC"1"
VALUE"0.1UF"
VOLTAGE"25V"
PACKAGE"0402"
CDS_LIB"passive"
CDS_LMAN_SYM_OUTLINE"-50,0,50,-50"
CLS_PN"G105-0B104-EK"
TOLERANCE"10%";
"2"
$PN"2"11;
"1"
$PN"1"12;
%"NLASB3157DFT2G_SC88"
"2","(-5000,2750)","0","interface","I491";
;
$LOCATION"U40"
CDS_LOCATION"U40"
$SEC"2"
CDS_SEC"2"
CLS_PN"G223-10187-01"
CDS_LMAN_SYM_OUTLINE"0,0,400,-500"
CDS_LIB"interface";
"VCC"
$PN"5"12;
"GND"
$PN"2"11;
%"GND_SG"
"1","(-4850,2000)","0","cls","I492";
;
HDL_POWER"SG"
CDS_LIB"cls"
CDS_LMAN_SYM_OUTLINE"0,0,100,-50"
BODY_TYPE"PLUMBING";
"SGND"11;
%"RESISTOR"
"1","(-7450,3500)","0","passive","I493";
;
$LOCATION"R464"
CDS_LOCATION"R464"
$SEC"1"
CDS_SEC"1"
PACKAGE"0402"
VALUE"0OHM"
NO_ASSY"TRUE"
CDS_LIB"passive"
CDS_LMAN_SYM_OUTLINE"-50,50,100,-50"
CLS_PN"G155-100R0-J0"
TOLERANCE"-";
"1"
$PN"1"95;
"2"
$PN"2"101;
%"RESISTOR"
"1","(-7450,2850)","0","passive","I494";
;
$LOCATION"R465"
CDS_LOCATION"R465"
$SEC"1"
CDS_SEC"1"
VALUE"0OHM"
NO_ASSY"TRUE"
PACKAGE"0402"
CDS_LIB"passive"
CDS_LMAN_SYM_OUTLINE"-50,50,100,-50"
CLS_PN"G155-100R0-J0"
TOLERANCE"-";
"1"
$PN"1"120;
"2"
$PN"2"100;
%"CONN_USB_14P_GH4_F_RA_TH"
"1","(-13750,10450)","0","connector","I495";
;
LOCATION"J13"
$SEC"1"
CDS_SEC"1"
CLS_PN"G200-13135-01"
VALUE"2169890002"
CDS_LMAN_SYM_OUTLINE"0,0,900,-1400"
CDS_LIB"connector";
"GH4"
$PN"GH4"27;
"GH3"
$PN"GH3"27;
"GH2"
$PN"GH2"27;
"GH1"
$PN"GH1"27;
"GND_4"
$PN"B12"27;
"VBUS_4"
$PN"B9"28;
"D2_N"
$PN"B7"132;
"D2_P"
$PN"B6"133;
"CC2"
$PN"B5"131;
"VBUS_3"
$PN"B4"28;
"GND_3"
$PN"B1"27;
"GND_2"
$PN"A12"27;
"VBUS_2"
$PN"A9"26;
"D1_N"
$PN"A7"135;
"D1_P"
$PN"A6"136;
"CC1"
$PN"A5"134;
"VBUS_1"
$PN"A4"26;
"GND_1"
$PN"A1"27;
%"GND_SG"
"1","(-11800,10000)","1","cls","I496";
;
HDL_POWER"SG"
BODY_TYPE"PLUMBING"
CDS_LMAN_SYM_OUTLINE"0,0,100,-50"
CDS_LIB"cls";
"SGND"4;
%"RESISTOR"
"2","(-14250,10050)","7","passive","I497";
;
LOCATION"R442"
$SEC"1"
CDS_SEC"1"
VALUE"5.1KOHM"
PACKAGE"0402"
CDS_LIB"passive"
CDS_LMAN_SYM_OUTLINE"-50,50,50,-100"
TOLERANCE"1%"
CLS_PN"G155-05101-01";
"1"
$PN"1"134;
"2"
$PN"2"3;
%"GND_SG"
"1","(-14650,10000)","7","cls","I498";
;
HDL_POWER"SG"
CDS_LIB"cls"
CDS_LMAN_SYM_OUTLINE"0,0,100,-50"
BODY_TYPE"PLUMBING";
"SGND"3;
%"GND_SG"
"1","(-10750,7200)","0","cls","I5";
;
HDL_POWER"SG"
CDS_LIB"cls"
CDS_LMAN_SYM_OUTLINE"0,0,100,-50"
BODY_TYPE"PLUMBING";
"SGND"2;
%"GND_SG"
"1","(-9700,7200)","0","cls","I6";
;
HDL_POWER"SG"
BODY_TYPE"PLUMBING"
CDS_LIB"cls"
CDS_LMAN_SYM_OUTLINE"0,0,100,-50";
"SGND"10;
%"FT4232HL_REEL_QFP64"
"1","(-7900,11550)","0","interface","I64";
;
$LOCATION"U18"
CDS_LOCATION"U18"
$SEC"1"
CDS_SEC"1"
VALUE"FT4232HL-REEL"
CLS_PN"G223-10282-01"
CDS_LMAN_SYM_OUTLINE"0,0,1000,-5000"
CDS_LIB"interface";
"TEST"
$PN"13"34;
"OSCO"
$PN"3"67;
"OSCI"
$PN"2"46;
"EEDATA"
$PN"61"65;
"EECLK"
$PN"62"66;
"EECS"
$PN"63"47;
"RESET* \B"
$PN"14"119;
"REF"
$PN"6"68;
"DP"
$PN"8"105;
"DM"
$PN"7"99;
"GND_8"
$PN"1"9;
"GND_7"
$PN"5"9;
"GND_6"
$PN"11"9;
"GND_5"
$PN"15"9;
"GND_4"
$PN"25"9;
"GND_3"
$PN"35"9;
"GND_2"
$PN"47"9;
"GND_1"
$PN"51"9;
"AGND"
$PN"10"9;
"VPHY"
$PN"4"114;
"VPLL"
$PN"9"107;
"VCORE_3"
$PN"12"81;
"VCORE_2"
$PN"37"81;
"VCORE_1"
$PN"64"81;
"VCCIO_4"
$PN"20"29;
"VCCIO_3"
$PN"31"29;
"VCCIO_2"
$PN"42"29;
"VCCIO_1"
$PN"56"29;
"VREGOUT"
$PN"49"81;
"VREGIN"
$PN"50"33;
"SUSPEND* \B"
$PN"36"0;
"PWREN* \B"
$PN"60"0;
"DDBUS7"
$PN"59"0;
"DDBUS6"
$PN"58"0;
"DDBUS5"
$PN"57"0;
"DDBUS4"
$PN"55"0;
"DDBUS3"
$PN"54"0;
"DDBUS2"
$PN"53"0;
"DDBUS1"
$PN"52"52;
"DDBUS0"
$PN"48"57;
"CDBUS7"
$PN"46"0;
"CDBUS6"
$PN"45"0;
"CDBUS5"
$PN"44"0;
"CDBUS4"
$PN"43"0;
"CDBUS3"
$PN"41"0;
"CDBUS2"
$PN"40"0;
"CDBUS1"
$PN"39"74;
"CDBUS0"
$PN"38"113;
"BDBUS7"
$PN"34"117;
"BDBUS6"
$PN"33"118;
"BDBUS5"
$PN"32"54;
"BDBUS4"
$PN"30"104;
"BDBUS3"
$PN"29"103;
"BDBUS2"
$PN"28"142;
"BDBUS1"
$PN"27"53;
"BDBUS0"
$PN"26"106;
"ADBUS7"
$PN"24"102;
"ADBUS6"
$PN"23"112;
"ADBUS5"
$PN"22"64;
"ADBUS4"
$PN"21"61;
"ADBUS3"
$PN"19"60;
"ADBUS2"
$PN"18"59;
"ADBUS1"
$PN"17"58;
"ADBUS0"
$PN"16"62;
%"CAPACITOR"
"1","(-10700,7400)","1","passive","I7";
;
$LOCATION"C86"
CDS_LOCATION"C86"
$SEC"1"
CDS_SEC"1"
PACKAGE"0201"
VALUE"18PF"
CLS_PN"G104-0A180-FJ"
CDS_LIB"passive"
CDS_LMAN_SYM_OUTLINE"0,50,50,-50"
TOLERANCE"5%";
"2"
$PN"2"46;
"1"
$PN"1"2;
%"XTAL_4"
"1","(-10500,8050)","0","clock","I8";
;
$LOCATION"Y2"
CDS_LOCATION"Y2"
$SEC"1"
CDS_SEC"1"
PART_NUMBER"7M12000031"
CLS_PN"G131-10038-02"
CDS_LMAN_SYM_OUTLINE"0,0,500,-500"
CDS_LIB"clock";
"4"
$PN"4"1;
"3"
$PN"3"67;
"2"
$PN"2"10;
"1"
$PN"1"46;
%"GND_SG"
"1","(-10900,7800)","0","cls","I9";
;
HDL_POWER"SG"
BODY_TYPE"PLUMBING"
CDS_LMAN_SYM_OUTLINE"0,0,100,-50"
CDS_LIB"cls";
"SGND"1;
%"GND_SG"
"1","(-6650,6550)","0","cls","I95";
;
HDL_POWER"SG"
BODY_TYPE"PLUMBING"
CDS_LIB"cls"
CDS_LMAN_SYM_OUTLINE"0,0,100,-50";
"SGND"9;
END.
